(kicad_pcb
	(version 20241229)
	(generator "pcbnew")
	(generator_version "9.0")
	(general
		(thickness 1.599998)
		(legacy_teardrops no)
	)
	(paper "A4")
	(title_block
		(title "Artix - Datacenter Secure Control Module (DC-SCM)")
		(date "2024-11-06")
		(rev "1.1.3")
		(comment 9 "footprints 443-447 of 544")
	)
	(layers
		(0 "F.Cu" signal)
		(4 "In1.Cu" signal)
		(6 "In2.Cu" signal)
		(8 "In3.Cu" signal)
		(10 "In4.Cu" signal)
		(12 "In5.Cu" signal)
		(14 "In6.Cu" signal)
		(2 "B.Cu" signal)
		(9 "F.Adhes" user "F.Adhesive")
		(11 "B.Adhes" user "B.Adhesive")
		(13 "F.Paste" user)
		(15 "B.Paste" user)
		(5 "F.SilkS" user "F.Silkscreen")
		(7 "B.SilkS" user "B.Silkscreen")
		(1 "F.Mask" user)
		(3 "B.Mask" user)
		(17 "Dwgs.User" user "User.Drawings")
		(19 "Cmts.User" user "User.Comments")
		(21 "Eco1.User" user "User.Eco1")
		(23 "Eco2.User" user "User.Eco2")
		(25 "Edge.Cuts" user)
		(27 "Margin" user)
		(31 "F.CrtYd" user "F.Courtyard")
		(29 "B.CrtYd" user "B.Courtyard")
		(35 "F.Fab" user)
		(33 "B.Fab" user)
	)
	(footprint "antmicro-footprints:C_0402_1005Metric"
		(layer "B.Cu")
		(at 134.774 127.514 -90)
		(descr "Capacitor SMD 0402")
		(tags "capacitor SMD 0402")
		(property "Reference" "C183"
			(at 1.086 2.974 90)
			(layer "B.SilkS")
			(effects
				(font
					(size 0.7 0.7)
					(thickness 0.15)
				)
				(justify left bottom mirror)
			)
		)
		(property "Value" "C_2u2_0402"
			(at 0 -1.4 90)
			(layer "B.Fab")
			(effects
				(font
					(size 0.7 0.7)
					(thickness 0.15)
				)
				(justify left bottom mirror)
			)
		)
		(property "Datasheet" "https://product.tdk.com/en/search/capacitor/ceramic/mlcc/info?part_no=C1005X5R1A225K050BC"
			(at 0 0 270)
			(layer "F.Fab")
			(hide yes)
			(effects
				(font
					(size 1.27 1.27)
					(thickness 0.15)
				)
			)
		)
		(property "Description" "SMD Multilayer Ceramic Capacitor, 2.2 µF, 10 V, 0402 [1005 Metric], ± 10%, X5R, C"
			(at 0 0 270)
			(layer "F.Fab")
			(hide yes)
			(effects
				(font
					(size 1.27 1.27)
					(thickness 0.15)
				)
			)
		)
		(property "Author" "Antmicro"
			(at 7.26 262.288 0)
			(layer "B.Fab")
			(hide yes)
			(effects
				(font
					(size 1 1)
					(thickness 0.15)
				)
				(justify mirror)
			)
		)
		(property "Dielectric" ""
			(at 7.26 262.288 0)
			(layer "B.Fab")
			(hide yes)
			(effects
				(font
					(size 1 1)
					(thickness 0.15)
				)
				(justify mirror)
			)
		)
		(property "License" "Apache-2.0"
			(at 7.26 262.288 0)
			(layer "B.Fab")
			(hide yes)
			(effects
				(font
					(size 1 1)
					(thickness 0.15)
				)
				(justify mirror)
			)
		)
		(property "MPN" "C1005X5R1A225K050BC"
			(at 7.26 262.288 0)
			(layer "B.Fab")
			(hide yes)
			(effects
				(font
					(size 1 1)
					(thickness 0.15)
				)
				(justify mirror)
			)
		)
		(property "Manufacturer" "TDK"
			(at 7.26 262.288 0)
			(layer "B.Fab")
			(hide yes)
			(effects
				(font
					(size 1 1)
					(thickness 0.15)
				)
				(justify mirror)
			)
		)
		(property "Val" "2u2"
			(at 7.26 262.288 0)
			(layer "B.Fab")
			(hide yes)
			(effects
				(font
					(size 1 1)
					(thickness 0.15)
				)
				(justify mirror)
			)
		)
		(property "Voltage" ""
			(at 7.26 262.288 0)
			(layer "B.Fab")
			(hide yes)
			(effects
				(font
					(size 1 1)
					(thickness 0.15)
				)
				(justify mirror)
			)
		)
		(sheetname "/Interfaces/")
		(sheetfile "interfaces.kicad_sch")
		(attr smd)
		(fp_rect
			(start -0.925 0.47)
			(end 0.925 -0.47)
			(stroke
				(width 0.05)
				(type default)
			)
			(fill no)
			(layer "B.CrtYd")
		)
		(fp_line
			(start -0.494 0.25)
			(end 0.504 0.25)
			(stroke
				(width 0.15)
				(type solid)
			)
			(layer "B.Fab")
		)
		(fp_line
			(start 0.504 0.25)
			(end 0.504 -0.248)
			(stroke
				(width 0.15)
				(type solid)
			)
			(layer "B.Fab")
		)
		(fp_line
			(start -0.494 -0.248)
			(end -0.494 0.25)
			(stroke
				(width 0.15)
				(type solid)
			)
			(layer "B.Fab")
		)
		(fp_line
			(start 0.504 -0.248)
			(end -0.494 -0.248)
			(stroke
				(width 0.15)
				(type solid)
			)
			(layer "B.Fab")
		)
		(pad "1" smd roundrect
			(at -0.48 0 270)
			(size 0.59 0.64)
			(layers "B.Cu" "B.Mask" "B.Paste")
			(roundrect_rratio 0.25)
			(net 1 "GND")
			(pintype "passive")
		)
		(pad "2" smd roundrect
			(at 0.48 0 270)
			(size 0.59 0.64)
			(layers "B.Cu" "B.Mask" "B.Paste")
			(roundrect_rratio 0.25)
			(net 2 "VCC3V3")
			(pintype "passive")
		)
	)
	(footprint "antmicro-footprints:C_0402_1005Metric"
		(layer "B.Cu")
		(at 136.774 127.514 -90)
		(descr "Capacitor SMD 0402")
		(tags "capacitor SMD 0402")
		(property "Reference" "C184"
			(at 1.086 2.974 90)
			(layer "B.SilkS")
			(effects
				(font
					(size 0.7 0.7)
					(thickness 0.15)
				)
				(justify left bottom mirror)
			)
		)
		(property "Value" "C_2u2_0402"
			(at 0 -1.4 90)
			(layer "B.Fab")
			(effects
				(font
					(size 0.7 0.7)
					(thickness 0.15)
				)
				(justify left bottom mirror)
			)
		)
		(property "Datasheet" "https://product.tdk.com/en/search/capacitor/ceramic/mlcc/info?part_no=C1005X5R1A225K050BC"
			(at 0 0 270)
			(layer "F.Fab")
			(hide yes)
			(effects
				(font
					(size 1.27 1.27)
					(thickness 0.15)
				)
			)
		)
		(property "Description" "SMD Multilayer Ceramic Capacitor, 2.2 µF, 10 V, 0402 [1005 Metric], ± 10%, X5R, C"
			(at 0 0 270)
			(layer "F.Fab")
			(hide yes)
			(effects
				(font
					(size 1.27 1.27)
					(thickness 0.15)
				)
			)
		)
		(property "Author" "Antmicro"
			(at 9.26 264.288 0)
			(layer "B.Fab")
			(hide yes)
			(effects
				(font
					(size 1 1)
					(thickness 0.15)
				)
				(justify mirror)
			)
		)
		(property "Dielectric" ""
			(at 9.26 264.288 0)
			(layer "B.Fab")
			(hide yes)
			(effects
				(font
					(size 1 1)
					(thickness 0.15)
				)
				(justify mirror)
			)
		)
		(property "License" "Apache-2.0"
			(at 9.26 264.288 0)
			(layer "B.Fab")
			(hide yes)
			(effects
				(font
					(size 1 1)
					(thickness 0.15)
				)
				(justify mirror)
			)
		)
		(property "MPN" "C1005X5R1A225K050BC"
			(at 9.26 264.288 0)
			(layer "B.Fab")
			(hide yes)
			(effects
				(font
					(size 1 1)
					(thickness 0.15)
				)
				(justify mirror)
			)
		)
		(property "Manufacturer" "TDK"
			(at 9.26 264.288 0)
			(layer "B.Fab")
			(hide yes)
			(effects
				(font
					(size 1 1)
					(thickness 0.15)
				)
				(justify mirror)
			)
		)
		(property "Val" "2u2"
			(at 9.26 264.288 0)
			(layer "B.Fab")
			(hide yes)
			(effects
				(font
					(size 1 1)
					(thickness 0.15)
				)
				(justify mirror)
			)
		)
		(property "Voltage" ""
			(at 9.26 264.288 0)
			(layer "B.Fab")
			(hide yes)
			(effects
				(font
					(size 1 1)
					(thickness 0.15)
				)
				(justify mirror)
			)
		)
		(sheetname "/Interfaces/")
		(sheetfile "interfaces.kicad_sch")
		(attr smd)
		(fp_rect
			(start -0.925 0.47)
			(end 0.925 -0.47)
			(stroke
				(width 0.05)
				(type default)
			)
			(fill no)
			(layer "B.CrtYd")
		)
		(fp_line
			(start -0.494 0.25)
			(end 0.504 0.25)
			(stroke
				(width 0.15)
				(type solid)
			)
			(layer "B.Fab")
		)
		(fp_line
			(start 0.504 0.25)
			(end 0.504 -0.248)
			(stroke
				(width 0.15)
				(type solid)
			)
			(layer "B.Fab")
		)
		(fp_line
			(start -0.494 -0.248)
			(end -0.494 0.25)
			(stroke
				(width 0.15)
				(type solid)
			)
			(layer "B.Fab")
		)
		(fp_line
			(start 0.504 -0.248)
			(end -0.494 -0.248)
			(stroke
				(width 0.15)
				(type solid)
			)
			(layer "B.Fab")
		)
		(pad "1" smd roundrect
			(at -0.48 0 270)
			(size 0.59 0.64)
			(layers "B.Cu" "B.Mask" "B.Paste")
			(roundrect_rratio 0.25)
			(net 1 "GND")
			(pintype "passive")
		)
		(pad "2" smd roundrect
			(at 0.48 0 270)
			(size 0.59 0.64)
			(layers "B.Cu" "B.Mask" "B.Paste")
			(roundrect_rratio 0.25)
			(net 2 "VCC3V3")
			(pintype "passive")
		)
	)
	(footprint "antmicro-footprints:C_0402_1005Metric"
		(layer "B.Cu")
		(at 138.774 123.014 180)
		(descr "Capacitor SMD 0402")
		(tags "capacitor SMD 0402")
		(property "Reference" "C185"
			(at 0.774 -0.386 0)
			(layer "B.SilkS")
			(effects
				(font
					(size 0.7 0.7)
					(thickness 0.15)
				)
				(justify left bottom mirror)
			)
		)
		(property "Value" "C_2u2_0402"
			(at 0 -1.4 0)
			(layer "B.Fab")
			(effects
				(font
					(size 0.7 0.7)
					(thickness 0.15)
				)
				(justify left bottom mirror)
			)
		)
		(property "Datasheet" "https://product.tdk.com/en/search/capacitor/ceramic/mlcc/info?part_no=C1005X5R1A225K050BC"
			(at 0 0 180)
			(layer "F.Fab")
			(hide yes)
			(effects
				(font
					(size 1.27 1.27)
					(thickness 0.15)
				)
			)
		)
		(property "Description" "SMD Multilayer Ceramic Capacitor, 2.2 µF, 10 V, 0402 [1005 Metric], ± 10%, X5R, C"
			(at 0 0 180)
			(layer "F.Fab")
			(hide yes)
			(effects
				(font
					(size 1.27 1.27)
					(thickness 0.15)
				)
			)
		)
		(property "Author" "Antmicro"
			(at 277.548 246.028 0)
			(layer "B.Fab")
			(hide yes)
			(effects
				(font
					(size 1 1)
					(thickness 0.15)
				)
				(justify mirror)
			)
		)
		(property "Dielectric" ""
			(at 277.548 246.028 0)
			(layer "B.Fab")
			(hide yes)
			(effects
				(font
					(size 1 1)
					(thickness 0.15)
				)
				(justify mirror)
			)
		)
		(property "License" "Apache-2.0"
			(at 277.548 246.028 0)
			(layer "B.Fab")
			(hide yes)
			(effects
				(font
					(size 1 1)
					(thickness 0.15)
				)
				(justify mirror)
			)
		)
		(property "MPN" "C1005X5R1A225K050BC"
			(at 277.548 246.028 0)
			(layer "B.Fab")
			(hide yes)
			(effects
				(font
					(size 1 1)
					(thickness 0.15)
				)
				(justify mirror)
			)
		)
		(property "Manufacturer" "TDK"
			(at 277.548 246.028 0)
			(layer "B.Fab")
			(hide yes)
			(effects
				(font
					(size 1 1)
					(thickness 0.15)
				)
				(justify mirror)
			)
		)
		(property "Val" "2u2"
			(at 277.548 246.028 0)
			(layer "B.Fab")
			(hide yes)
			(effects
				(font
					(size 1 1)
					(thickness 0.15)
				)
				(justify mirror)
			)
		)
		(property "Voltage" ""
			(at 277.548 246.028 0)
			(layer "B.Fab")
			(hide yes)
			(effects
				(font
					(size 1 1)
					(thickness 0.15)
				)
				(justify mirror)
			)
		)
		(sheetname "/Interfaces/")
		(sheetfile "interfaces.kicad_sch")
		(attr smd)
		(fp_rect
			(start -0.925 0.47)
			(end 0.925 -0.47)
			(stroke
				(width 0.05)
				(type default)
			)
			(fill no)
			(layer "B.CrtYd")
		)
		(fp_line
			(start 0.504 0.25)
			(end 0.504 -0.248)
			(stroke
				(width 0.15)
				(type solid)
			)
			(layer "B.Fab")
		)
		(fp_line
			(start 0.504 -0.248)
			(end -0.494 -0.248)
			(stroke
				(width 0.15)
				(type solid)
			)
			(layer "B.Fab")
		)
		(fp_line
			(start -0.494 0.25)
			(end 0.504 0.25)
			(stroke
				(width 0.15)
				(type solid)
			)
			(layer "B.Fab")
		)
		(fp_line
			(start -0.494 -0.248)
			(end -0.494 0.25)
			(stroke
				(width 0.15)
				(type solid)
			)
			(layer "B.Fab")
		)
		(pad "1" smd roundrect
			(at -0.48 0 180)
			(size 0.59 0.64)
			(layers "B.Cu" "B.Mask" "B.Paste")
			(roundrect_rratio 0.25)
			(net 1 "GND")
			(pintype "passive")
		)
		(pad "2" smd roundrect
			(at 0.48 0 180)
			(size 0.59 0.64)
			(layers "B.Cu" "B.Mask" "B.Paste")
			(roundrect_rratio 0.25)
			(net 2 "VCC3V3")
			(pintype "passive")
		)
	)
	(footprint "antmicro-footprints:C_0402_1005Metric"
		(layer "B.Cu")
		(at 135.774 127.514 -90)
		(descr "Capacitor SMD 0402")
		(tags "capacitor SMD 0402")
		(property "Reference" "C186"
			(at 1.086 2.974 90)
			(layer "B.SilkS")
			(effects
				(font
					(size 0.7 0.7)
					(thickness 0.15)
				)
				(justify left bottom mirror)
			)
		)
		(property "Value" "C_100n_6V3_0402"
			(at 0 -1.4 90)
			(layer "B.Fab")
			(effects
				(font
					(size 0.7 0.7)
					(thickness 0.15)
				)
				(justify left bottom mirror)
			)
		)
		(property "Datasheet" "https://www.passivecomponent.com/wp-content/uploads/datasheet/WTC_MLCC_General_Purpose.pdf"
			(at 0 0 270)
			(layer "F.Fab")
			(hide yes)
			(effects
				(font
					(size 1.27 1.27)
					(thickness 0.15)
				)
			)
		)
		(property "Description" "SMT Multilayer Ceramic Capacitor, 0.1 µF, 6.3 V, 0402 [1005 Metric], ± 10%, X5R, Walsin MLCC"
			(at 0 0 270)
			(layer "F.Fab")
			(hide yes)
			(effects
				(font
					(size 1.27 1.27)
					(thickness 0.15)
				)
			)
		)
		(property "Author" "Antmicro"
			(at 8.26 263.288 0)
			(layer "B.Fab")
			(hide yes)
			(effects
				(font
					(size 1 1)
					(thickness 0.15)
				)
				(justify mirror)
			)
		)
		(property "Dielectric" ""
			(at 8.26 263.288 0)
			(layer "B.Fab")
			(hide yes)
			(effects
				(font
					(size 1 1)
					(thickness 0.15)
				)
				(justify mirror)
			)
		)
		(property "License" "Apache-2.0"
			(at 8.26 263.288 0)
			(layer "B.Fab")
			(hide yes)
			(effects
				(font
					(size 1 1)
					(thickness 0.15)
				)
				(justify mirror)
			)
		)
		(property "MPN" "0402X104K6R3CT"
			(at 8.26 263.288 0)
			(layer "B.Fab")
			(hide yes)
			(effects
				(font
					(size 1 1)
					(thickness 0.15)
				)
				(justify mirror)
			)
		)
		(property "Manufacturer" "Walsin"
			(at 8.26 263.288 0)
			(layer "B.Fab")
			(hide yes)
			(effects
				(font
					(size 1 1)
					(thickness 0.15)
				)
				(justify mirror)
			)
		)
		(property "Public" "False"
			(at 8.26 263.288 0)
			(layer "B.Fab")
			(hide yes)
			(effects
				(font
					(size 1 1)
					(thickness 0.15)
				)
				(justify mirror)
			)
		)
		(property "Val" "100n"
			(at 8.26 263.288 0)
			(layer "B.Fab")
			(hide yes)
			(effects
				(font
					(size 1 1)
					(thickness 0.15)
				)
				(justify mirror)
			)
		)
		(property "Voltage" ""
			(at 8.26 263.288 0)
			(layer "B.Fab")
			(hide yes)
			(effects
				(font
					(size 1 1)
					(thickness 0.15)
				)
				(justify mirror)
			)
		)
		(sheetname "/Interfaces/")
		(sheetfile "interfaces.kicad_sch")
		(attr smd)
		(fp_rect
			(start -0.925 0.47)
			(end 0.925 -0.47)
			(stroke
				(width 0.05)
				(type default)
			)
			(fill no)
			(layer "B.CrtYd")
		)
		(fp_line
			(start -0.494 0.25)
			(end 0.504 0.25)
			(stroke
				(width 0.15)
				(type solid)
			)
			(layer "B.Fab")
		)
		(fp_line
			(start 0.504 0.25)
			(end 0.504 -0.248)
			(stroke
				(width 0.15)
				(type solid)
			)
			(layer "B.Fab")
		)
		(fp_line
			(start -0.494 -0.248)
			(end -0.494 0.25)
			(stroke
				(width 0.15)
				(type solid)
			)
			(layer "B.Fab")
		)
		(fp_line
			(start 0.504 -0.248)
			(end -0.494 -0.248)
			(stroke
				(width 0.15)
				(type solid)
			)
			(layer "B.Fab")
		)
		(pad "1" smd roundrect
			(at -0.48 0 270)
			(size 0.59 0.64)
			(layers "B.Cu" "B.Mask" "B.Paste")
			(roundrect_rratio 0.25)
			(net 1 "GND")
			(pintype "passive")
		)
		(pad "2" smd roundrect
			(at 0.48 0 270)
			(size 0.59 0.64)
			(layers "B.Cu" "B.Mask" "B.Paste")
			(roundrect_rratio 0.25)
			(net 2 "VCC3V3")
			(pintype "passive")
		)
	)
	(footprint "antmicro-footprints:C_0402_1005Metric"
		(layer "B.Cu")
		(at 133.574 122.514)
		(descr "Capacitor SMD 0402")
		(tags "capacitor SMD 0402")
		(property "Reference" "C187"
			(at -3.674 0.386 0)
			(layer "B.SilkS")
			(effects
				(font
					(size 0.7 0.7)
					(thickness 0.15)
				)
				(justify right bottom mirror)
			)
		)
		(property "Value" "C_100n_6V3_0402"
			(at 0 -1.4 0)
			(layer "B.Fab")
			(effects
				(font
					(size 0.7 0.7)
					(thickness 0.15)
				)
				(justify right bottom mirror)
			)
		)
		(property "Datasheet" "https://www.passivecomponent.com/wp-content/uploads/datasheet/WTC_MLCC_General_Purpose.pdf"
			(at 0 0 0)
			(layer "F.Fab")
			(hide yes)
			(effects
				(font
					(size 1.27 1.27)
					(thickness 0.15)
				)
			)
		)
		(property "Description" "SMT Multilayer Ceramic Capacitor, 0.1 µF, 6.3 V, 0402 [1005 Metric], ± 10%, X5R, Walsin MLCC"
			(at 0 0 0)
			(layer "F.Fab")
			(hide yes)
			(effects
				(font
					(size 1.27 1.27)
					(thickness 0.15)
				)
			)
		)
		(property "Author" "Antmicro"
			(at 0 0 0)
			(layer "B.Fab")
			(hide yes)
			(effects
				(font
					(size 1 1)
					(thickness 0.15)
				)
				(justify mirror)
			)
		)
		(property "Dielectric" ""
			(at 0 0 0)
			(layer "B.Fab")
			(hide yes)
			(effects
				(font
					(size 1 1)
					(thickness 0.15)
				)
				(justify mirror)
			)
		)
		(property "License" "Apache-2.0"
			(at 0 0 0)
			(layer "B.Fab")
			(hide yes)
			(effects
				(font
					(size 1 1)
					(thickness 0.15)
				)
				(justify mirror)
			)
		)
		(property "MPN" "0402X104K6R3CT"
			(at 0 0 0)
			(layer "B.Fab")
			(hide yes)
			(effects
				(font
					(size 1 1)
					(thickness 0.15)
				)
				(justify mirror)
			)
		)
		(property "Manufacturer" "Walsin"
			(at 0 0 0)
			(layer "B.Fab")
			(hide yes)
			(effects
				(font
					(size 1 1)
					(thickness 0.15)
				)
				(justify mirror)
			)
		)
		(property "Public" "False"
			(at 0 0 0)
			(layer "B.Fab")
			(hide yes)
			(effects
				(font
					(size 1 1)
					(thickness 0.15)
				)
				(justify mirror)
			)
		)
		(property "Val" "100n"
			(at 0 0 0)
			(layer "B.Fab")
			(hide yes)
			(effects
				(font
					(size 1 1)
					(thickness 0.15)
				)
				(justify mirror)
			)
		)
		(property "Voltage" ""
			(at 0 0 0)
			(layer "B.Fab")
			(hide yes)
			(effects
				(font
					(size 1 1)
					(thickness 0.15)
				)
				(justify mirror)
			)
		)
		(sheetname "/Interfaces/")
		(sheetfile "interfaces.kicad_sch")
		(attr smd)
		(fp_rect
			(start -0.925 0.47)
			(end 0.925 -0.47)
			(stroke
				(width 0.05)
				(type default)
			)
			(fill no)
			(layer "B.CrtYd")
		)
		(fp_line
			(start -0.494 -0.248)
			(end -0.494 0.25)
			(stroke
				(width 0.15)
				(type solid)
			)
			(layer "B.Fab")
		)
		(fp_line
			(start -0.494 0.25)
			(end 0.504 0.25)
			(stroke
				(width 0.15)
				(type solid)
			)
			(layer "B.Fab")
		)
		(fp_line
			(start 0.504 -0.248)
			(end -0.494 -0.248)
			(stroke
				(width 0.15)
				(type solid)
			)
			(layer "B.Fab")
		)
		(fp_line
			(start 0.504 0.25)
			(end 0.504 -0.248)
			(stroke
				(width 0.15)
				(type solid)
			)
			(layer "B.Fab")
		)
		(pad "1" smd roundrect
			(at -0.48 0)
			(size 0.59 0.64)
			(layers "B.Cu" "B.Mask" "B.Paste")
			(roundrect_rratio 0.25)
			(net 1 "GND")
			(pintype "passive")
		)
		(pad "2" smd roundrect
			(at 0.48 0)
			(size 0.59 0.64)
			(layers "B.Cu" "B.Mask" "B.Paste")
			(roundrect_rratio 0.25)
			(net 2 "VCC3V3")
			(pintype "passive")
		)
	)
)
